#ISCELL
  pure_quanta quanta_title_block_c *
  *
#CELL
  pure_quanta genoa_sp5 *
  page59_i1
#ISCELL
  pure_quanta_power universal_gnd *
  page59_i10
#ISCELL
  pure_quanta_power universal_gnd *
  page59_i11
#ISCELL
  pure_quanta_power universal_gnd *
  page59_i12
#CELL
  pure_quanta genoa_sp5 *
  page59_i2
#CELL
  pure_quanta genoa_sp5 *
  page59_i3
#CELL
  pure_quanta genoa_sp5 *
  page59_i4
#ISCELL
  pure_quanta_power universal_gnd *
  page59_i5
#ISCELL
  pure_quanta_power universal_gnd *
  page59_i6
#ISCELL
  pure_quanta_power universal_gnd *
  page59_i7
#ISCELL
  pure_quanta_power universal_gnd *
  page59_i8
#ISCELL
  pure_quanta_power universal_gnd *
  page59_i9
